#ISCELL
  pure_quanta quanta_title_block_c *
  *
#ISCELL
  pure_quanta_power cad_note *
  *
#CELL
  pure_quanta genoa_sp5 *
  page47_i159
#ISCELL
  mstr_standard offpage *
  page47_i160
#ISCELL
  mstr_standard tap *
  page47_i161
#ISCELL
  mstr_standard tap *
  page47_i162
#ISCELL
  mstr_standard tap *
  page47_i163
#ISCELL
  mstr_standard tap *
  page47_i164
#ISCELL
  mstr_standard tap *
  page47_i165
#ISCELL
  mstr_standard tap *
  page47_i166
#ISCELL
  mstr_standard tap *
  page47_i167
#ISCELL
  mstr_standard tap *
  page47_i168
#ISCELL
  mstr_standard tap *
  page47_i169
#ISCELL
  mstr_standard tap *
  page47_i170
#ISCELL
  mstr_standard tap *
  page47_i171
#ISCELL
  mstr_standard tap *
  page47_i172
#ISCELL
  mstr_standard tap *
  page47_i173
#ISCELL
  mstr_standard tap *
  page47_i174
#ISCELL
  mstr_standard tap *
  page47_i175
#ISCELL
  mstr_standard tap *
  page47_i176
#ISCELL
  mstr_standard tap *
  page47_i177
#ISCELL
  mstr_standard tap *
  page47_i178
#ISCELL
  mstr_standard tap *
  page47_i179
#ISCELL
  mstr_standard tap *
  page47_i180
#ISCELL
  mstr_standard tap *
  page47_i181
#ISCELL
  mstr_standard tap *
  page47_i182
#ISCELL
  mstr_standard tap *
  page47_i183
#ISCELL
  mstr_standard tap *
  page47_i184
#ISCELL
  mstr_standard tap *
  page47_i185
#ISCELL
  mstr_standard tap *
  page47_i186
#ISCELL
  mstr_standard tap *
  page47_i187
#ISCELL
  mstr_standard tap *
  page47_i188
#ISCELL
  mstr_standard tap *
  page47_i189
#ISCELL
  mstr_standard tap *
  page47_i190
#ISCELL
  mstr_standard tap *
  page47_i191
#ISCELL
  mstr_standard tap *
  page47_i192
#ISCELL
  mstr_standard tap *
  page47_i193
#ISCELL
  mstr_standard offpage *
  page47_i194
#ISCELL
  mstr_standard offpage *
  page47_i195
#ISCELL
  mstr_standard tap *
  page47_i196
#ISCELL
  mstr_standard tap *
  page47_i197
#ISCELL
  mstr_standard tap *
  page47_i198
#ISCELL
  mstr_standard tap *
  page47_i199
#ISCELL
  mstr_standard tap *
  page47_i200
#ISCELL
  mstr_standard tap *
  page47_i201
#ISCELL
  mstr_standard tap *
  page47_i202
#ISCELL
  mstr_standard tap *
  page47_i203
#ISCELL
  mstr_standard tap *
  page47_i204
#ISCELL
  mstr_standard tap *
  page47_i205
#ISCELL
  mstr_standard tap *
  page47_i206
#ISCELL
  mstr_standard tap *
  page47_i207
#ISCELL
  mstr_standard tap *
  page47_i208
#ISCELL
  mstr_standard tap *
  page47_i209
#ISCELL
  mstr_standard tap *
  page47_i210
#ISCELL
  mstr_standard tap *
  page47_i211
#ISCELL
  mstr_standard tap *
  page47_i212
#ISCELL
  mstr_standard tap *
  page47_i213
#ISCELL
  mstr_standard tap *
  page47_i214
#ISCELL
  mstr_standard tap *
  page47_i215
#ISCELL
  mstr_standard tap *
  page47_i216
#ISCELL
  mstr_standard tap *
  page47_i217
#ISCELL
  mstr_standard tap *
  page47_i218
#ISCELL
  mstr_standard tap *
  page47_i219
#ISCELL
  mstr_standard tap *
  page47_i220
#ISCELL
  mstr_standard tap *
  page47_i221
#ISCELL
  mstr_standard tap *
  page47_i222
#ISCELL
  mstr_standard tap *
  page47_i223
#ISCELL
  mstr_standard tap *
  page47_i224
#ISCELL
  mstr_standard tap *
  page47_i225
#ISCELL
  mstr_standard tap *
  page47_i226
#ISCELL
  mstr_standard tap *
  page47_i227
#ISCELL
  mstr_standard tap *
  page47_i228
#ISCELL
  mstr_standard tap *
  page47_i229
#ISCELL
  mstr_standard tap *
  page47_i230
#ISCELL
  mstr_standard tap *
  page47_i231
#ISCELL
  mstr_standard tap *
  page47_i232
#ISCELL
  mstr_standard offpage *
  page47_i233
#ISCELL
  mstr_standard tap *
  page47_i234
#ISCELL
  mstr_standard tap *
  page47_i235
#ISCELL
  mstr_standard tap *
  page47_i236
#ISCELL
  mstr_standard tap *
  page47_i237
#ISCELL
  mstr_standard tap *
  page47_i238
#ISCELL
  mstr_standard tap *
  page47_i239
#ISCELL
  mstr_standard tap *
  page47_i240
#ISCELL
  mstr_standard tap *
  page47_i241
#ISCELL
  mstr_standard tap *
  page47_i242
#ISCELL
  mstr_standard tap *
  page47_i243
#ISCELL
  mstr_standard tap *
  page47_i244
#ISCELL
  mstr_standard tap *
  page47_i245
#ISCELL
  mstr_standard tap *
  page47_i246
#ISCELL
  mstr_standard tap *
  page47_i247
#ISCELL
  mstr_standard tap *
  page47_i248
#ISCELL
  mstr_standard tap *
  page47_i249
#ISCELL
  mstr_standard tap *
  page47_i250
#ISCELL
  mstr_standard tap *
  page47_i251
#ISCELL
  mstr_standard tap *
  page47_i252
#ISCELL
  mstr_standard tap *
  page47_i253
#ISCELL
  mstr_standard tap *
  page47_i254
#ISCELL
  mstr_standard tap *
  page47_i255
#ISCELL
  mstr_standard tap *
  page47_i256
#ISCELL
  mstr_standard tap *
  page47_i257
#ISCELL
  mstr_standard tap *
  page47_i258
#ISCELL
  mstr_standard tap *
  page47_i259
#ISCELL
  mstr_standard tap *
  page47_i260
#ISCELL
  mstr_standard tap *
  page47_i261
#ISCELL
  mstr_standard tap *
  page47_i262
#ISCELL
  mstr_standard tap *
  page47_i263
#ISCELL
  mstr_standard tap *
  page47_i264
#ISCELL
  mstr_standard tap *
  page47_i265
#ISCELL
  mstr_standard tap *
  page47_i266
#ISCELL
  mstr_standard tap *
  page47_i267
#ISCELL
  mstr_standard tap *
  page47_i268
#ISCELL
  mstr_standard tap *
  page47_i269
#ISCELL
  mstr_standard tap *
  page47_i270
#ISCELL
  mstr_standard tap *
  page47_i271
#ISCELL
  mstr_standard tap *
  page47_i272
#ISCELL
  mstr_standard tap *
  page47_i273
#ISCELL
  mstr_standard tap *
  page47_i274
#ISCELL
  mstr_standard tap *
  page47_i275
#ISCELL
  mstr_standard tap *
  page47_i276
#ISCELL
  mstr_standard tap *
  page47_i277
#ISCELL
  mstr_standard tap *
  page47_i278
#ISCELL
  mstr_standard tap *
  page47_i279
#ISCELL
  standard offpage *
  page47_i280
#ISCELL
  standard offpage *
  page47_i281
#ISCELL
  standard offpage *
  page47_i282
#ISCELL
  standard offpage *
  page47_i283
#ISCELL
  mstr_standard tap *
  page47_i284
#ISCELL
  mstr_standard tap *
  page47_i285
#ISCELL
  mstr_standard tap *
  page47_i286
#ISCELL
  mstr_standard tap *
  page47_i287
#ISCELL
  mstr_standard tap *
  page47_i288
#ISCELL
  mstr_standard tap *
  page47_i289
#ISCELL
  mstr_standard tap *
  page47_i290
#ISCELL
  mstr_standard tap *
  page47_i291
#ISCELL
  mstr_standard tap *
  page47_i292
#ISCELL
  mstr_standard tap *
  page47_i293
#ISCELL
  mstr_standard tap *
  page47_i294
#ISCELL
  mstr_standard tap *
  page47_i295
#ISCELL
  mstr_standard tap *
  page47_i296
#ISCELL
  mstr_standard tap *
  page47_i297
#ISCELL
  mstr_standard tap *
  page47_i298
#ISCELL
  mstr_standard tap *
  page47_i299
#ISCELL
  mstr_standard tap *
  page47_i300
#ISCELL
  mstr_standard tap *
  page47_i301
#ISCELL
  standard offpage *
  page47_i302
#ISCELL
  standard offpage *
  page47_i303
#ISCELL
  standard offpage *
  page47_i304
#ISCELL
  standard offpage *
  page47_i305
#ISCELL
  standard offpage *
  page47_i306
#ISCELL
  standard offpage *
  page47_i307
#ISCELL
  standard offpage *
  page47_i308
#ISCELL
  mstr_standard offpage *
  page47_i309
#ISCELL
  standard offpage *
  page47_i310
#ISCELL
  standard offpage *
  page47_i311
#ISCELL
  standard offpage *
  page47_i312
#ISCELL
  standard offpage *
  page47_i313
#CELL
  pure_quanta q_res *
  page47_i314
#ISCELL
  standard offpage *
  page47_i315
#ISCELL
  mstr_standard offpage *
  page47_i316
